# S9S_MB_2U (Grand Teton) — schematic netlist excerpt (pin names and nets, part order shuffled) for the footprints in the layout excerpt that follows; sources: Cadence DE-HDL packaged netlist, KiCad conversion of 03242023_DA0F0TMBIJ0_F0T_Motherboard_J_brd_V01_OCP.brd

R1592  Q_RES  10K 1% CHIP  pkg 0402LF  page 155 : A = P3V3_OCP_SFF ; B = PU_OCP_SFF_WAKE_OE

U204  74LVC1G126SE7  74LVC1G126SE-7 IC  pkg SOT353_0-65_2X1-25  page 151
  OE  = FM_UART_EN
  A  = UART_BMC_BIC_R_RX
  GND  = GND
  Y  = UART_BMC_BIC_R_BUF_RX
  VCC  = P3V3_AUX

(kicad_pcb
	(version 20260206)
	(generator "pcbnew")
	(generator_version "10.0")
	(general
		(thickness 1.6)
		(legacy_teardrops no)
	)
	(paper "A4")
	(title_block
		(title "03242023_DA0F0TMBIJ0_F0T_Motherboard_J_brd_V01_OCP.brd")
		(comment 1 "Grand Teton / footprints 2887-2888 of 6105")
	)
	(layers
		(0 "F.Cu" signal "TOP")
		(4 "In1.Cu" signal "GND")
		(6 "In2.Cu" signal "IN1")
		(8 "In3.Cu" signal "GND1")
		(10 "In4.Cu" signal "IN2")
		(12 "In5.Cu" signal "GND2")
		(14 "In6.Cu" signal "IN3")
		(16 "In7.Cu" signal "GND3")
		(18 "In8.Cu" signal "VCC")
		(20 "In9.Cu" signal "VCC1")
		(22 "In10.Cu" signal "GND4")
		(24 "In11.Cu" signal "IN4")
		(26 "In12.Cu" signal "GND5")
		(28 "In13.Cu" signal "IN5")
		(30 "In14.Cu" signal "GND6")
		(32 "In15.Cu" signal "IN6")
		(34 "In16.Cu" signal "GND7")
		(2 "B.Cu" signal "BOTTOM")
		(9 "F.Adhes" user "F.Adhesive")
		(11 "B.Adhes" user "B.Adhesive")
		(13 "F.Paste" user "Package Geometry/Pastemask Top")
		(15 "B.Paste" user "Package Geometry/Pastemask Bottom")
		(5 "F.SilkS" user "Ref Des/Silkscreen Top")
		(7 "B.SilkS" user "Ref Des/Silkscreen Bottom")
		(1 "F.Mask" user "Board Geometry/Soldermask Top")
		(3 "B.Mask" user "Board Geometry/Soldermask Bottom")
		(17 "Dwgs.User" user "User.Drawings")
		(19 "Cmts.User" user "User.Comments")
		(21 "Eco1.User" user "User.Eco1")
		(23 "Eco2.User" user "User.Eco2")
		(25 "Edge.Cuts" user "Board Geometry/Outline")
		(27 "Margin" user)
		(31 "F.CrtYd" user "Package Geometry/Place Bound Top")
		(29 "B.CrtYd" user "Package Geometry/Place Bound Bottom")
		(35 "F.Fab" user "Ref Des/Assembly Top")
		(33 "B.Fab" user "Ref Des/Assembly Bottom")
	)
	(footprint ""
		(layer "F.Cu")
		(at 363.64672 -403.322028)
		(property "Reference" "U204"
			(at -0.13208 1.83261 0)
			(unlocked yes)
			(layer "F.SilkS")
			(effects
				(font
					(size 0.7874 0.5842)
					(thickness 0.1524)
				)
				(justify left)
			)
		)
		(property "Value" ""
			(at 0 0 0)
			(layer "F.Fab")
			(effects
				(font
					(size 1.27 1.27)
				)
			)
		)
		(duplicate_pad_numbers_are_jumpers no)
		(fp_line
			(start -1.400048 1.100074)
			(end -1.400048 -1.100074)
			(stroke
				(width 0.1524)
				(type default)
			)
			(layer "F.SilkS")
		)
		(fp_line
			(start 1.400048 -1.100074)
			(end -1.400048 -1.100074)
			(stroke
				(width 0.1524)
				(type default)
			)
			(layer "F.SilkS")
		)
		(fp_line
			(start 1.400048 -1.100074)
			(end 1.400048 1.100074)
			(stroke
				(width 0.1524)
				(type default)
			)
			(layer "F.SilkS")
		)
		(fp_line
			(start 1.400048 1.100074)
			(end -1.400048 1.100074)
			(stroke
				(width 0.1524)
				(type default)
			)
			(layer "F.SilkS")
		)
		(fp_poly
			(pts
				(xy -0.95631 -1.391412) (xy -1.46431 -2.407412) (xy -0.44831 -2.407412)
			)
			(stroke
				(width 0)
				(type default)
			)
			(fill yes)
			(layer "F.SilkS")
		)
		(fp_line
			(start -0.674878 -1.100074)
			(end 0.674878 -1.100074)
			(stroke
				(width 0.1)
				(type default)
			)
			(layer "F.Fab")
		)
		(fp_line
			(start -0.674878 1.100074)
			(end -0.674878 -1.100074)
			(stroke
				(width 0.1)
				(type default)
			)
			(layer "F.Fab")
		)
		(fp_line
			(start 0.674878 -1.100074)
			(end 0.674878 1.100074)
			(stroke
				(width 0.1)
				(type default)
			)
			(layer "F.Fab")
		)
		(fp_line
			(start 0.674878 1.100074)
			(end -0.674878 1.100074)
			(stroke
				(width 0.1)
				(type default)
			)
			(layer "F.Fab")
		)
		(fp_poly
			(pts
				(xy -1.590548 -0.649986) (xy -2.606548 -1.157986) (xy -2.606548 -0.141986)
			)
			(stroke
				(width 0)
				(type default)
			)
			(fill yes)
			(layer "F.Fab")
		)
		(pad "1" smd rect
			(at -0.94996 -0.649986 270)
			(size 0.4318 0.6096)
			(layers "F.Cu" "F.Mask" "F.Paste")
			(net "FM_UART_EN")
		)
		(pad "2" smd rect
			(at -0.94996 0 270)
			(size 0.4318 0.6096)
			(layers "F.Cu" "F.Mask" "F.Paste")
			(net "UART_BMC_BIC_R_RX")
		)
		(pad "3" smd rect
			(at -0.94996 0.649986 270)
			(size 0.4318 0.6096)
			(layers "F.Cu" "F.Mask" "F.Paste")
			(net "GND")
		)
		(pad "4" smd rect
			(at 0.94996 0.649986 270)
			(size 0.4318 0.6096)
			(layers "F.Cu" "F.Mask" "F.Paste")
			(net "UART_BMC_BIC_R_BUF_RX")
		)
		(pad "5" smd rect
			(at 0.94996 -0.649986 270)
			(size 0.4318 0.6096)
			(layers "F.Cu" "F.Mask" "F.Paste")
			(net "P3V3_AUX")
		)
	)
	(footprint ""
		(layer "F.Cu")
		(at 466.67547 -48.940212 180)
		(property "Reference" "R1592"
			(at 0 0 180)
			(layer "F.SilkS")
			(hide yes)
			(effects
				(font
					(size 1.27 1.27)
				)
			)
		)
		(property "Value" ""
			(at 0 0 180)
			(layer "F.Fab")
			(effects
				(font
					(size 1.27 1.27)
				)
			)
		)
		(duplicate_pad_numbers_are_jumpers no)
		(fp_line
			(start 0.7874 0.4064)
			(end -0.7874 0.4064)
			(stroke
				(width 0.1524)
				(type default)
			)
			(layer "F.SilkS")
		)
		(fp_line
			(start 0.7874 -0.4064)
			(end 0.7874 0.4064)
			(stroke
				(width 0.1524)
				(type default)
			)
			(layer "F.SilkS")
		)
		(fp_line
			(start -0.7874 0.4064)
			(end -0.7874 -0.4064)
			(stroke
				(width 0.1524)
				(type default)
			)
			(layer "F.SilkS")
		)
		(fp_line
			(start -0.7874 -0.4064)
			(end 0.7874 -0.4064)
			(stroke
				(width 0.1524)
				(type default)
			)
			(layer "F.SilkS")
		)
		(fp_line
			(start 0.67945 0.3048)
			(end 0.120396 0.3048)
			(stroke
				(width 0.1)
				(type default)
			)
			(layer "F.Fab")
		)
		(fp_line
			(start 0.67945 -0.3048)
			(end 0.67945 0.3048)
			(stroke
				(width 0.1)
				(type default)
			)
			(layer "F.Fab")
		)
		(fp_line
			(start 0.12065 -0.2794)
			(end 0.12065 -0.3048)
			(stroke
				(width 0.1)
				(type default)
			)
			(layer "F.Fab")
		)
		(fp_line
			(start 0.12065 -0.3048)
			(end 0.67945 -0.3048)
			(stroke
				(width 0.1)
				(type default)
			)
			(layer "F.Fab")
		)
		(fp_line
			(start 0.120396 0.3048)
			(end 0.120396 0.2794)
			(stroke
				(width 0.1)
				(type default)
			)
			(layer "F.Fab")
		)
		(fp_line
			(start 0.120396 0.2794)
			(end -0.12065 0.2794)
			(stroke
				(width 0.1)
				(type default)
			)
			(layer "F.Fab")
		)
		(fp_line
			(start -0.12065 0.3048)
			(end -0.67945 0.3048)
			(stroke
				(width 0.1)
				(type default)
			)
			(layer "F.Fab")
		)
		(fp_line
			(start -0.12065 0.2794)
			(end -0.12065 0.3048)
			(stroke
				(width 0.1)
				(type default)
			)
			(layer "F.Fab")
		)
		(fp_line
			(start -0.12065 -0.2794)
			(end 0.12065 -0.2794)
			(stroke
				(width 0.1)
				(type default)
			)
			(layer "F.Fab")
		)
		(fp_line
			(start -0.12065 -0.305054)
			(end -0.12065 -0.2794)
			(stroke
				(width 0.1)
				(type default)
			)
			(layer "F.Fab")
		)
		(fp_line
			(start -0.67945 0.3048)
			(end -0.67945 -0.305054)
			(stroke
				(width 0.1)
				(type default)
			)
			(layer "F.Fab")
		)
		(fp_line
			(start -0.67945 -0.305054)
			(end -0.12065 -0.305054)
			(stroke
				(width 0.1)
				(type default)
			)
			(layer "F.Fab")
		)
		(pad "1" smd circle
			(at -0.40005 0 180)
			(size 0 0)
			(layers "F.Cu" "F.Mask" "F.Paste")
			(net "P3V3_OCP_SFF")
		)
		(pad "2" smd circle
			(at 0.40005 0 180)
			(size 0 0)
			(layers "F.Cu" "F.Mask" "F.Paste")
			(net "PU_OCP_SFF_WAKE_OE")
		)
	)
)
